# S9S_MB_2U (Grand Teton) — schematic netlist excerpt (pin names and nets, part order shuffled) for the footprints in the layout excerpt that follows; sources: Cadence DE-HDL packaged netlist, KiCad conversion of 03242023_DA0F0TMBIJ0_F0T_Motherboard_J_brd_V01_OCP.brd

R685  Q_RES  0 5% EMPTY  pkg 0402LF  page 229 : A = I3C_SPD_DDREFGH_CPU0_R_SDA ; B = I3C_SPD_DDREFGH_CPU0_LVC1_R_SDA
R1416  Q_RES  2K 1% EMPTY  pkg 0402LF  page 219 : A = RST_CPU1_LVC1_R_N ; B = GND
PC238_P0_8  Q_CAP  22UF 16V 20% X6S  pkg C0805  page 270 : A = SW_P12V_PVCCIN_CPU0_FLT ; B = GND

(kicad_pcb
	(version 20260206)
	(generator "pcbnew")
	(generator_version "10.0")
	(general
		(thickness 1.6)
		(legacy_teardrops no)
	)
	(paper "A4")
	(title_block
		(title "03242023_DA0F0TMBIJ0_F0T_Motherboard_J_brd_V01_OCP.brd")
		(comment 1 "Grand Teton / footprints 5592-5594 of 6105")
	)
	(layers
		(0 "F.Cu" signal "TOP")
		(4 "In1.Cu" signal "GND")
		(6 "In2.Cu" signal "IN1")
		(8 "In3.Cu" signal "GND1")
		(10 "In4.Cu" signal "IN2")
		(12 "In5.Cu" signal "GND2")
		(14 "In6.Cu" signal "IN3")
		(16 "In7.Cu" signal "GND3")
		(18 "In8.Cu" signal "VCC")
		(20 "In9.Cu" signal "VCC1")
		(22 "In10.Cu" signal "GND4")
		(24 "In11.Cu" signal "IN4")
		(26 "In12.Cu" signal "GND5")
		(28 "In13.Cu" signal "IN5")
		(30 "In14.Cu" signal "GND6")
		(32 "In15.Cu" signal "IN6")
		(34 "In16.Cu" signal "GND7")
		(2 "B.Cu" signal "BOTTOM")
		(9 "F.Adhes" user "F.Adhesive")
		(11 "B.Adhes" user "B.Adhesive")
		(13 "F.Paste" user "Package Geometry/Pastemask Top")
		(15 "B.Paste" user "Package Geometry/Pastemask Bottom")
		(5 "F.SilkS" user "Ref Des/Silkscreen Top")
		(7 "B.SilkS" user "Ref Des/Silkscreen Bottom")
		(1 "F.Mask" user "Board Geometry/Soldermask Top")
		(3 "B.Mask" user "Board Geometry/Soldermask Bottom")
		(17 "Dwgs.User" user "User.Drawings")
		(19 "Cmts.User" user "User.Comments")
		(21 "Eco1.User" user "User.Eco1")
		(23 "Eco2.User" user "User.Eco2")
		(25 "Edge.Cuts" user "Board Geometry/Outline")
		(27 "Margin" user)
		(31 "F.CrtYd" user "Package Geometry/Place Bound Top")
		(29 "B.CrtYd" user "Package Geometry/Place Bound Bottom")
		(35 "F.Fab" user "Ref Des/Assembly Top")
		(33 "B.Fab" user "Ref Des/Assembly Bottom")
	)
	(footprint ""
		(layer "B.Cu")
		(at 304.138584 -151.719534 -90)
		(property "Reference" "R685"
			(at 0 0 90)
			(layer "B.SilkS")
			(hide yes)
			(effects
				(font
					(size 1.27 1.27)
				)
				(justify mirror)
			)
		)
		(property "Value" ""
			(at 0 0 90)
			(layer "B.Fab")
			(effects
				(font
					(size 1.27 1.27)
				)
				(justify mirror)
			)
		)
		(duplicate_pad_numbers_are_jumpers no)
		(fp_line
			(start -0.7874 0.4064)
			(end 0.7874 0.4064)
			(stroke
				(width 0.1524)
				(type default)
			)
			(layer "B.SilkS")
		)
		(fp_line
			(start 0.7874 0.4064)
			(end 0.7874 -0.4064)
			(stroke
				(width 0.1524)
				(type default)
			)
			(layer "B.SilkS")
		)
		(fp_line
			(start -0.7874 -0.4064)
			(end -0.7874 0.4064)
			(stroke
				(width 0.1524)
				(type default)
			)
			(layer "B.SilkS")
		)
		(fp_line
			(start 0.7874 -0.4064)
			(end -0.7874 -0.4064)
			(stroke
				(width 0.1524)
				(type default)
			)
			(layer "B.SilkS")
		)
		(fp_line
			(start -0.67945 0.3048)
			(end -0.120396 0.3048)
			(stroke
				(width 0.1)
				(type default)
			)
			(layer "B.Fab")
		)
		(fp_line
			(start -0.120396 0.3048)
			(end -0.120396 0.2794)
			(stroke
				(width 0.1)
				(type default)
			)
			(layer "B.Fab")
		)
		(fp_line
			(start 0.12065 0.3048)
			(end 0.67945 0.3048)
			(stroke
				(width 0.1)
				(type default)
			)
			(layer "B.Fab")
		)
		(fp_line
			(start 0.67945 0.3048)
			(end 0.67945 -0.305054)
			(stroke
				(width 0.1)
				(type default)
			)
			(layer "B.Fab")
		)
		(fp_line
			(start -0.120396 0.2794)
			(end 0.12065 0.2794)
			(stroke
				(width 0.1)
				(type default)
			)
			(layer "B.Fab")
		)
		(fp_line
			(start 0.12065 0.2794)
			(end 0.12065 0.3048)
			(stroke
				(width 0.1)
				(type default)
			)
			(layer "B.Fab")
		)
		(fp_line
			(start -0.12065 -0.2794)
			(end -0.12065 -0.3048)
			(stroke
				(width 0.1)
				(type default)
			)
			(layer "B.Fab")
		)
		(fp_line
			(start 0.12065 -0.2794)
			(end -0.12065 -0.2794)
			(stroke
				(width 0.1)
				(type default)
			)
			(layer "B.Fab")
		)
		(fp_line
			(start -0.67945 -0.3048)
			(end -0.67945 0.3048)
			(stroke
				(width 0.1)
				(type default)
			)
			(layer "B.Fab")
		)
		(fp_line
			(start -0.12065 -0.3048)
			(end -0.67945 -0.3048)
			(stroke
				(width 0.1)
				(type default)
			)
			(layer "B.Fab")
		)
		(fp_line
			(start 0.12065 -0.305054)
			(end 0.12065 -0.2794)
			(stroke
				(width 0.1)
				(type default)
			)
			(layer "B.Fab")
		)
		(fp_line
			(start 0.67945 -0.305054)
			(end 0.12065 -0.305054)
			(stroke
				(width 0.1)
				(type default)
			)
			(layer "B.Fab")
		)
		(pad "1" smd circle
			(at 0.40005 0 90)
			(size 0 0)
			(layers "B.Cu" "B.Mask" "B.Paste")
			(net "I3C_SPD_DDREFGH_CPU0_R_SDA")
		)
		(pad "2" smd circle
			(at -0.40005 0 90)
			(size 0 0)
			(layers "B.Cu" "B.Mask" "B.Paste")
			(net "I3C_SPD_DDREFGH_CPU0_LVC1_R_SDA")
		)
	)
	(footprint ""
		(layer "B.Cu")
		(at 188.46546 -104.823768)
		(property "Reference" "R1416"
			(at 0 0 0)
			(layer "B.SilkS")
			(hide yes)
			(effects
				(font
					(size 1.27 1.27)
				)
				(justify mirror)
			)
		)
		(property "Value" ""
			(at 0 0 0)
			(layer "B.Fab")
			(effects
				(font
					(size 1.27 1.27)
				)
				(justify mirror)
			)
		)
		(duplicate_pad_numbers_are_jumpers no)
		(fp_line
			(start -0.7874 -0.4064)
			(end -0.7874 0.4064)
			(stroke
				(width 0.1524)
				(type default)
			)
			(layer "B.SilkS")
		)
		(fp_line
			(start -0.7874 0.4064)
			(end 0.7874 0.4064)
			(stroke
				(width 0.1524)
				(type default)
			)
			(layer "B.SilkS")
		)
		(fp_line
			(start 0.7874 -0.4064)
			(end -0.7874 -0.4064)
			(stroke
				(width 0.1524)
				(type default)
			)
			(layer "B.SilkS")
		)
		(fp_line
			(start 0.7874 0.4064)
			(end 0.7874 -0.4064)
			(stroke
				(width 0.1524)
				(type default)
			)
			(layer "B.SilkS")
		)
		(fp_line
			(start -0.67945 -0.3048)
			(end -0.67945 0.3048)
			(stroke
				(width 0.1)
				(type default)
			)
			(layer "B.Fab")
		)
		(fp_line
			(start -0.67945 0.3048)
			(end -0.120396 0.3048)
			(stroke
				(width 0.1)
				(type default)
			)
			(layer "B.Fab")
		)
		(fp_line
			(start -0.12065 -0.3048)
			(end -0.67945 -0.3048)
			(stroke
				(width 0.1)
				(type default)
			)
			(layer "B.Fab")
		)
		(fp_line
			(start -0.12065 -0.2794)
			(end -0.12065 -0.3048)
			(stroke
				(width 0.1)
				(type default)
			)
			(layer "B.Fab")
		)
		(fp_line
			(start -0.120396 0.2794)
			(end 0.12065 0.2794)
			(stroke
				(width 0.1)
				(type default)
			)
			(layer "B.Fab")
		)
		(fp_line
			(start -0.120396 0.3048)
			(end -0.120396 0.2794)
			(stroke
				(width 0.1)
				(type default)
			)
			(layer "B.Fab")
		)
		(fp_line
			(start 0.12065 -0.305054)
			(end 0.12065 -0.2794)
			(stroke
				(width 0.1)
				(type default)
			)
			(layer "B.Fab")
		)
		(fp_line
			(start 0.12065 -0.2794)
			(end -0.12065 -0.2794)
			(stroke
				(width 0.1)
				(type default)
			)
			(layer "B.Fab")
		)
		(fp_line
			(start 0.12065 0.2794)
			(end 0.12065 0.3048)
			(stroke
				(width 0.1)
				(type default)
			)
			(layer "B.Fab")
		)
		(fp_line
			(start 0.12065 0.3048)
			(end 0.67945 0.3048)
			(stroke
				(width 0.1)
				(type default)
			)
			(layer "B.Fab")
		)
		(fp_line
			(start 0.67945 -0.305054)
			(end 0.12065 -0.305054)
			(stroke
				(width 0.1)
				(type default)
			)
			(layer "B.Fab")
		)
		(fp_line
			(start 0.67945 0.3048)
			(end 0.67945 -0.305054)
			(stroke
				(width 0.1)
				(type default)
			)
			(layer "B.Fab")
		)
		(pad "1" smd circle
			(at 0.40005 0 180)
			(size 0 0)
			(layers "B.Cu" "B.Mask" "B.Paste")
			(net "RST_CPU1_LVC1_R_N")
		)
		(pad "2" smd circle
			(at -0.40005 0 180)
			(size 0 0)
			(layers "B.Cu" "B.Mask" "B.Paste")
			(net "GND")
		)
	)
	(footprint ""
		(layer "B.Cu")
		(at 388.989824 -342.936576 90)
		(property "Reference" "PC238_P0_8"
			(at 0 0 90)
			(layer "B.SilkS")
			(hide yes)
			(effects
				(font
					(size 1.27 1.27)
				)
				(justify mirror)
			)
		)
		(property "Value" ""
			(at 0 0 90)
			(layer "B.Fab")
			(effects
				(font
					(size 1.27 1.27)
				)
				(justify mirror)
			)
		)
		(duplicate_pad_numbers_are_jumpers no)
		(fp_line
			(start 1.524 -0.762)
			(end -1.524 -0.762)
			(stroke
				(width 0.1524)
				(type default)
			)
			(layer "B.SilkS")
		)
		(fp_line
			(start -1.524 -0.762)
			(end -1.524 0.762)
			(stroke
				(width 0.1524)
				(type default)
			)
			(layer "B.SilkS")
		)
		(fp_line
			(start 1.524 0.762)
			(end 1.524 -0.762)
			(stroke
				(width 0.1524)
				(type default)
			)
			(layer "B.SilkS")
		)
		(fp_line
			(start -1.524 0.762)
			(end 1.524 0.762)
			(stroke
				(width 0.1524)
				(type default)
			)
			(layer "B.SilkS")
		)
		(fp_line
			(start 1.1049 -0.724916)
			(end 1.1049 0.724916)
			(stroke
				(width 0.1)
				(type default)
			)
			(layer "B.Fab")
		)
		(fp_line
			(start -1.1049 -0.724916)
			(end 1.1049 -0.724916)
			(stroke
				(width 0.1)
				(type default)
			)
			(layer "B.Fab")
		)
		(fp_line
			(start 1.1049 0.724916)
			(end -1.1049 0.724916)
			(stroke
				(width 0.1)
				(type default)
			)
			(layer "B.Fab")
		)
		(fp_line
			(start -1.1049 0.724916)
			(end -1.1049 -0.724916)
			(stroke
				(width 0.1)
				(type default)
			)
			(layer "B.Fab")
		)
		(pad "1" smd rect
			(at 0.889 0 90)
			(size 1.016 1.27)
			(layers "B.Cu" "B.Mask" "B.Paste")
			(net "SW_P12V_PVCCIN_CPU0_FLT")
		)
		(pad "2" smd rect
			(at -0.889 0 90)
			(size 1.016 1.27)
			(layers "B.Cu" "B.Mask" "B.Paste")
			(net "GND")
		)
	)
)
